(kicad_pcb
	(version 20260206)
	(generator "pcbnew")
	(generator_version "10.0")
	(general
		(thickness 1.6)
		(legacy_teardrops no)
	)
	(paper "A4")
	(title_block
		(title "Bryce Canyon_F.DPB_16315-1-OCP.brd")
		(comment 1 "Bryce Canyon / footprints 979-984 of 2223")
	)
	(layers
		(0 "F.Cu" signal "TOP")
		(4 "In1.Cu" signal "L2GND")
		(6 "In2.Cu" signal "L3")
		(8 "In3.Cu" signal "L4GND")
		(10 "In4.Cu" signal "L5")
		(12 "In5.Cu" signal "L6VCC")
		(14 "In6.Cu" signal "L7VCC")
		(16 "In7.Cu" signal "L8")
		(18 "In8.Cu" signal "L9GND")
		(20 "In9.Cu" signal "L10")
		(22 "In10.Cu" signal "L11GND")
		(2 "B.Cu" signal "BOTTOM")
		(9 "F.Adhes" user "F.Adhesive")
		(11 "B.Adhes" user "B.Adhesive")
		(13 "F.Paste" user "Package Geometry/Pastemask Top")
		(15 "B.Paste" user "Package Geometry/Pastemask Bottom")
		(5 "F.SilkS" user "Ref Des/Silkscreen Top")
		(7 "B.SilkS" user "Ref Des/Silkscreen Bottom")
		(1 "F.Mask" user "Board Geometry/Soldermask Top")
		(3 "B.Mask" user "Board Geometry/Soldermask Bottom")
		(17 "Dwgs.User" user "User.Drawings")
		(19 "Cmts.User" user "User.Comments")
		(21 "Eco1.User" user "User.Eco1")
		(23 "Eco2.User" user "User.Eco2")
		(25 "Edge.Cuts" user "Board Geometry/Outline")
		(27 "Margin" user)
		(31 "F.CrtYd" user "Package Geometry/Place Bound Top")
		(29 "B.CrtYd" user "Package Geometry/Place Bound Bottom")
		(35 "F.Fab" user "Ref Des/Assembly Top")
		(33 "B.Fab" user "Ref Des/Assembly Bottom")
	)
	(footprint ""
		(layer "F.Cu")
		(at 351.4598 -141.1986)
		(property "Reference" "Q222"
			(at 0 0 0)
			(layer "F.SilkS")
			(hide yes)
			(effects
				(font
					(size 1.27 1.27)
				)
			)
		)
		(property "Value" "IRFH8201TRPBF-GP"
			(at -4.2164 -4.3688 0)
			(unlocked yes)
			(layer "F.Fab")
			(hide yes)
			(effects
				(font
					(size 1.016 1.016)
					(thickness 0.1524)
				)
			)
		)
		(property "Device Type" "PPAK-5PH42"
			(at -4.2164 -5.8928 0)
			(unlocked yes)
			(layer "F.Fab")
			(hide yes)
			(effects
				(font
					(size 1.016 1.016)
					(thickness 0.1524)
				)
			)
		)
		(duplicate_pad_numbers_are_jumpers no)
		(fp_line
			(start -3.0353 4.9276)
			(end -3.0353 3.9624)
			(stroke
				(width 0.3302)
				(type default)
			)
			(layer "F.SilkS")
		)
		(fp_line
			(start -2.8956 -2.794)
			(end 2.8956 -2.794)
			(stroke
				(width 0.1524)
				(type default)
			)
			(layer "F.SilkS")
		)
		(fp_line
			(start -2.8956 4.826)
			(end -2.8956 -2.794)
			(stroke
				(width 0.1524)
				(type default)
			)
			(layer "F.SilkS")
		)
		(fp_line
			(start -1.9431 4.9276)
			(end -3.0353 4.9276)
			(stroke
				(width 0.3302)
				(type default)
			)
			(layer "F.SilkS")
		)
		(fp_line
			(start 2.8956 -2.794)
			(end 2.8956 4.826)
			(stroke
				(width 0.1524)
				(type default)
			)
			(layer "F.SilkS")
		)
		(fp_line
			(start 2.8956 4.826)
			(end -2.8956 4.826)
			(stroke
				(width 0.1524)
				(type default)
			)
			(layer "F.SilkS")
		)
		(fp_poly
			(pts
				(xy -2.3622 5.334) (xy -1.4986 5.334) (xy -1.9304 4.9022)
			)
			(stroke
				(width 0)
				(type default)
			)
			(fill yes)
			(layer "F.SilkS")
		)
		(fp_poly
			(pts
				(xy -2.6416 -0.3556) (xy -0.3556 -0.3556) (xy -0.3556 -2.54) (xy -2.6416 -2.54)
			)
			(stroke
				(width 0)
				(type default)
			)
			(fill yes)
			(layer "F.Paste")
		)
		(fp_poly
			(pts
				(xy -2.6416 2.54) (xy -0.3556 2.54) (xy -0.3556 0.3556) (xy -2.6416 0.3556)
			)
			(stroke
				(width 0)
				(type default)
			)
			(fill yes)
			(layer "F.Paste")
		)
		(fp_poly
			(pts
				(xy 0.3556 -0.3556) (xy 2.6416 -0.3556) (xy 2.6416 -2.54) (xy 0.3556 -2.54)
			)
			(stroke
				(width 0)
				(type default)
			)
			(fill yes)
			(layer "F.Paste")
		)
		(fp_poly
			(pts
				(xy 0.3556 2.54) (xy 2.6416 2.54) (xy 2.6416 0.3556) (xy 0.3556 0.3556)
			)
			(stroke
				(width 0)
				(type default)
			)
			(fill yes)
			(layer "F.Paste")
		)
		(fp_rect
			(start -2.5781 3.9878)
			(end 2.5781 -2.1082)
			(stroke
				(width 0)
				(type default)
			)
			(fill no)
			(layer "F.CrtYd")
		)
		(fp_poly
			(pts
				(xy -3.1496 5.08) (xy -3.1496 -3.048) (xy 3.1496 -3.048) (xy 3.1496 3.9751) (xy 2.5781 3.9751) (xy 2.5781 -2.1082)
				(xy -2.5781 -2.1082) (xy -2.5781 3.9878) (xy 3.1496 3.9878) (xy 3.1496 5.08)
			)
			(stroke
				(width 0)
				(type default)
			)
			(fill no)
			(layer "F.CrtYd")
		)
		(fp_rect
			(start -3.1496 5.08)
			(end 3.1496 -3.048)
			(stroke
				(width 0)
				(type default)
			)
			(fill no)
			(layer "F.Fab")
		)
		(pad "1" smd rect
			(at -1.905 3.81)
			(size 0.762 1.524)
			(layers "F.Cu" "F.Mask" "F.Paste")
			(net "P12V_B_COMP")
		)
		(pad "2" smd rect
			(at -0.635 3.81)
			(size 0.762 1.524)
			(layers "F.Cu" "F.Mask" "F.Paste")
			(net "P12V_B_COMP")
		)
		(pad "3" smd rect
			(at 0.635 3.81)
			(size 0.762 1.524)
			(layers "F.Cu" "F.Mask" "F.Paste")
			(net "P12V_B_COMP")
		)
		(pad "4" smd rect
			(at 1.905 3.81)
			(size 0.762 1.524)
			(layers "F.Cu" "F.Mask" "F.Paste")
			(net "MB1_12V_CTRL_GATE1")
		)
		(pad "5" smd rect
			(at 0 0)
			(size 5.2832 5.08)
			(layers "F.Cu" "F.Mask" "F.Paste")
			(net "MB1_P12V_B_R")
		)
		(pad "6" smd rect
			(at 0.635 -2.032)
			(size 0.0254 0.0254)
			(layers "F.Cu" "F.Mask" "F.Paste")
			(net "MB1_P12V_B_R")
		)
		(pad "7" smd rect
			(at -0.635 -2.032)
			(size 0.0254 0.0254)
			(layers "F.Cu" "F.Mask" "F.Paste")
			(net "MB1_P12V_B_R")
		)
		(pad "8" smd rect
			(at -1.905 -2.032)
			(size 0.0254 0.0254)
			(layers "F.Cu" "F.Mask" "F.Paste")
			(net "MB1_P12V_B_R")
		)
	)
	(footprint ""
		(layer "F.Cu")
		(at 44.466002 -148.64715 180)
		(property "Reference" "R1240"
			(at 0 0 180)
			(layer "F.SilkS")
			(hide yes)
			(effects
				(font
					(size 1.27 1.27)
				)
			)
		)
		(property "Value" "619KR2F-GP"
			(at 0.064008 -3.993896 180)
			(unlocked yes)
			(layer "F.Fab")
			(hide yes)
			(effects
				(font
					(size 1.016 1.016)
					(thickness 0.1524)
				)
			)
		)
		(property "Device Type" "R402H16"
			(at 0.064008 -5.517896 180)
			(unlocked yes)
			(layer "F.Fab")
			(hide yes)
			(effects
				(font
					(size 1.016 1.016)
					(thickness 0.1524)
				)
			)
		)
		(duplicate_pad_numbers_are_jumpers no)
		(fp_line
			(start 0.508 -0.9398)
			(end -0.508 -0.9398)
			(stroke
				(width 0.1524)
				(type default)
			)
			(layer "F.SilkS")
		)
		(fp_line
			(start -0.508 -0.9398)
			(end -0.508 0.9398)
			(stroke
				(width 0.1524)
				(type default)
			)
			(layer "F.SilkS")
		)
		(fp_rect
			(start -0.508 0.9398)
			(end 0.508 -0.9398)
			(stroke
				(width 0)
				(type default)
			)
			(fill no)
			(layer "F.CrtYd")
		)
		(fp_rect
			(start -0.508 0.9398)
			(end 0.508 -0.9398)
			(stroke
				(width 0)
				(type default)
			)
			(fill no)
			(layer "F.Fab")
		)
		(pad "1" smd custom
			(at 0 -0.4445 180)
			(size 0.1397 0.1397)
			(layers "F.Cu" "F.Mask" "F.Paste")
			(net "P5V_B_RF")
			(options
				(clearance outline)
				(anchor circle)
			)
			(primitives
				(gr_poly
					(pts
						(arc
							(start -0.1778 -0.2794)
							(mid -0.249642 -0.249642)
							(end -0.2794 -0.1778)
						)
						(arc
							(start -0.2794 0.1778)
							(mid -0.249642 0.249642)
							(end -0.1778 0.2794)
						)
						(arc
							(start 0.1778 0.2794)
							(mid 0.249642 0.249642)
							(end 0.2794 0.1778)
						)
						(arc
							(start 0.2794 -0.1778)
							(mid 0.249642 -0.249642)
							(end 0.1778 -0.2794)
						)
					)
					(width 0)
					(fill yes)
				)
			)
		)
		(pad "2" smd custom
			(at 0 0.4445 180)
			(size 0.1397 0.1397)
			(layers "F.Cu" "F.Mask" "F.Paste")
			(net "AGND_P5V_B")
			(options
				(clearance outline)
				(anchor circle)
			)
			(primitives
				(gr_poly
					(pts
						(arc
							(start -0.1778 -0.2794)
							(mid -0.249642 -0.249642)
							(end -0.2794 -0.1778)
						)
						(arc
							(start -0.2794 0.1778)
							(mid -0.249642 0.249642)
							(end -0.1778 0.2794)
						)
						(arc
							(start 0.1778 0.2794)
							(mid 0.249642 0.249642)
							(end 0.2794 0.1778)
						)
						(arc
							(start 0.2794 -0.1778)
							(mid 0.249642 -0.249642)
							(end 0.1778 -0.2794)
						)
					)
					(width 0)
					(fill yes)
				)
			)
		)
	)
	(footprint ""
		(layer "F.Cu")
		(at 232.791 -244.1194 180)
		(property "Reference" "R69"
			(at 0 0 180)
			(layer "F.SilkS")
			(hide yes)
			(effects
				(font
					(size 1.27 1.27)
				)
			)
		)
		(property "Value" "4K7R2F-GP"
			(at 0.064008 -3.993896 180)
			(unlocked yes)
			(layer "F.Fab")
			(hide yes)
			(effects
				(font
					(size 1.016 1.016)
					(thickness 0.1524)
				)
			)
		)
		(property "Device Type" "R402H16"
			(at 0.064008 -5.517896 180)
			(unlocked yes)
			(layer "F.Fab")
			(hide yes)
			(effects
				(font
					(size 1.016 1.016)
					(thickness 0.1524)
				)
			)
		)
		(duplicate_pad_numbers_are_jumpers no)
		(fp_line
			(start 0.508 -0.9398)
			(end -0.508 -0.9398)
			(stroke
				(width 0.1524)
				(type default)
			)
			(layer "F.SilkS")
		)
		(fp_line
			(start -0.508 -0.9398)
			(end -0.508 0.9398)
			(stroke
				(width 0.1524)
				(type default)
			)
			(layer "F.SilkS")
		)
		(fp_rect
			(start -0.508 0.9398)
			(end 0.508 -0.9398)
			(stroke
				(width 0)
				(type default)
			)
			(fill no)
			(layer "F.CrtYd")
		)
		(fp_rect
			(start -0.508 0.9398)
			(end 0.508 -0.9398)
			(stroke
				(width 0)
				(type default)
			)
			(fill no)
			(layer "F.Fab")
		)
		(pad "1" smd custom
			(at 0 -0.4445 180)
			(size 0.1397 0.1397)
			(layers "F.Cu" "F.Mask" "F.Paste")
			(net "IO_EXP1_A2")
			(options
				(clearance outline)
				(anchor circle)
			)
			(primitives
				(gr_poly
					(pts
						(arc
							(start -0.1778 -0.2794)
							(mid -0.249642 -0.249642)
							(end -0.2794 -0.1778)
						)
						(arc
							(start -0.2794 0.1778)
							(mid -0.249642 0.249642)
							(end -0.1778 0.2794)
						)
						(arc
							(start 0.1778 0.2794)
							(mid 0.249642 0.249642)
							(end 0.2794 0.1778)
						)
						(arc
							(start 0.2794 -0.1778)
							(mid 0.249642 -0.249642)
							(end 0.1778 -0.2794)
						)
					)
					(width 0)
					(fill yes)
				)
			)
		)
		(pad "2" smd custom
			(at 0 0.4445 180)
			(size 0.1397 0.1397)
			(layers "F.Cu" "F.Mask" "F.Paste")
			(net "GND")
			(options
				(clearance outline)
				(anchor circle)
			)
			(primitives
				(gr_poly
					(pts
						(arc
							(start -0.1778 -0.2794)
							(mid -0.249642 -0.249642)
							(end -0.2794 -0.1778)
						)
						(arc
							(start -0.2794 0.1778)
							(mid -0.249642 0.249642)
							(end -0.1778 0.2794)
						)
						(arc
							(start 0.1778 0.2794)
							(mid 0.249642 0.249642)
							(end 0.2794 0.1778)
						)
						(arc
							(start 0.2794 -0.1778)
							(mid 0.249642 -0.249642)
							(end 0.1778 -0.2794)
						)
					)
					(width 0)
					(fill yes)
				)
			)
		)
	)
	(footprint ""
		(layer "F.Cu")
		(at 162.378898 -295.064942 90)
		(property "Reference" "R226"
			(at 0 0 90)
			(layer "F.SilkS")
			(hide yes)
			(effects
				(font
					(size 1.27 1.27)
				)
			)
		)
		(property "Value" "220R3F-1-GP"
			(at -0.0254 -2.5146 90)
			(unlocked yes)
			(layer "F.Fab")
			(hide yes)
			(effects
				(font
					(size 1.016 1.016)
					(thickness 0.1524)
				)
			)
		)
		(property "Device Type" "R603H22"
			(at -0.0254 -4.0386 90)
			(unlocked yes)
			(layer "F.Fab")
			(hide yes)
			(effects
				(font
					(size 1.016 1.016)
					(thickness 0.1524)
				)
			)
		)
		(duplicate_pad_numbers_are_jumpers no)
		(fp_line
			(start 0.2032 0)
			(end 0.4826 0)
			(stroke
				(width 0.2032)
				(type default)
			)
			(layer "F.SilkS")
		)
		(fp_line
			(start -0.4826 0)
			(end -0.2032 0)
			(stroke
				(width 0.2032)
				(type default)
			)
			(layer "F.SilkS")
		)
		(fp_rect
			(start -0.5842 1.3335)
			(end 0.5842 -1.3335)
			(stroke
				(width 0)
				(type default)
			)
			(fill no)
			(layer "F.CrtYd")
		)
		(fp_rect
			(start -0.5842 1.3335)
			(end 0.5842 -1.3335)
			(stroke
				(width 0)
				(type default)
			)
			(fill no)
			(layer "F.Fab")
		)
		(pad "1" smd custom
			(at 0 -0.762 90)
			(size 0.2159 0.2159)
			(layers "F.Cu" "F.Mask" "F.Paste")
			(net "HDD_PRSNT_4")
			(options
				(clearance outline)
				(anchor circle)
			)
			(primitives
				(gr_poly
					(pts
						(arc
							(start -0.3302 -0.4318)
							(mid -0.402042 -0.402042)
							(end -0.4318 -0.3302)
						)
						(arc
							(start -0.4318 0.3302)
							(mid -0.402042 0.402042)
							(end -0.3302 0.4318)
						)
						(arc
							(start 0.3302 0.4318)
							(mid 0.402042 0.402042)
							(end 0.4318 0.3302)
						)
						(arc
							(start 0.4318 -0.3302)
							(mid 0.402042 -0.402042)
							(end 0.3302 -0.4318)
						)
					)
					(width 0)
					(fill yes)
				)
			)
		)
		(pad "2" smd custom
			(at 0 0.762 90)
			(size 0.2159 0.2159)
			(layers "F.Cu" "F.Mask" "F.Paste")
			(net "DRIVE_A_4_INS")
			(options
				(clearance outline)
				(anchor circle)
			)
			(primitives
				(gr_poly
					(pts
						(arc
							(start -0.3302 -0.4318)
							(mid -0.402042 -0.402042)
							(end -0.4318 -0.3302)
						)
						(arc
							(start -0.4318 0.3302)
							(mid -0.402042 0.402042)
							(end -0.3302 0.4318)
						)
						(arc
							(start 0.3302 0.4318)
							(mid 0.402042 0.402042)
							(end 0.4318 0.3302)
						)
						(arc
							(start 0.4318 -0.3302)
							(mid 0.402042 -0.402042)
							(end 0.3302 -0.4318)
						)
					)
					(width 0)
					(fill yes)
				)
			)
		)
	)
	(footprint ""
		(layer "F.Cu")
		(at 174.895002 -242.25377)
		(property "Reference" "R223"
			(at 0 0 0)
			(layer "F.SilkS")
			(hide yes)
			(effects
				(font
					(size 1.27 1.27)
				)
			)
		)
		(property "Value" "130R3F-GP"
			(at -0.0254 -2.5146 0)
			(unlocked yes)
			(layer "F.Fab")
			(hide yes)
			(effects
				(font
					(size 1.016 1.016)
					(thickness 0.1524)
				)
			)
		)
		(property "Device Type" "R603H22"
			(at -0.0254 -4.0386 0)
			(unlocked yes)
			(layer "F.Fab")
			(hide yes)
			(effects
				(font
					(size 1.016 1.016)
					(thickness 0.1524)
				)
			)
		)
		(duplicate_pad_numbers_are_jumpers no)
		(fp_line
			(start -0.4826 0)
			(end -0.2032 0)
			(stroke
				(width 0.2032)
				(type default)
			)
			(layer "F.SilkS")
		)
		(fp_line
			(start 0.2032 0)
			(end 0.4826 0)
			(stroke
				(width 0.2032)
				(type default)
			)
			(layer "F.SilkS")
		)
		(fp_rect
			(start -0.5842 1.3335)
			(end 0.5842 -1.3335)
			(stroke
				(width 0)
				(type default)
			)
			(fill no)
			(layer "F.CrtYd")
		)
		(fp_rect
			(start -0.5842 1.3335)
			(end 0.5842 -1.3335)
			(stroke
				(width 0)
				(type default)
			)
			(fill no)
			(layer "F.Fab")
		)
		(pad "1" smd custom
			(at 0 -0.762)
			(size 0.2159 0.2159)
			(layers "F.Cu" "F.Mask" "F.Paste")
			(net "P5V_A_1")
			(options
				(clearance outline)
				(anchor circle)
			)
			(primitives
				(gr_poly
					(pts
						(arc
							(start -0.3302 -0.4318)
							(mid -0.402042 -0.402042)
							(end -0.4318 -0.3302)
						)
						(arc
							(start -0.4318 0.3302)
							(mid -0.402042 0.402042)
							(end -0.3302 0.4318)
						)
						(arc
							(start 0.3302 0.4318)
							(mid 0.402042 0.402042)
							(end 0.4318 0.3302)
						)
						(arc
							(start 0.4318 -0.3302)
							(mid 0.402042 -0.402042)
							(end 0.3302 -0.4318)
						)
					)
					(width 0)
					(fill yes)
				)
			)
		)
		(pad "2" smd custom
			(at 0 0.762)
			(size 0.2159 0.2159)
			(layers "F.Cu" "F.Mask" "F.Paste")
			(net "FLT_HDD5")
			(options
				(clearance outline)
				(anchor circle)
			)
			(primitives
				(gr_poly
					(pts
						(arc
							(start -0.3302 -0.4318)
							(mid -0.402042 -0.402042)
							(end -0.4318 -0.3302)
						)
						(arc
							(start -0.4318 0.3302)
							(mid -0.402042 0.402042)
							(end -0.3302 0.4318)
						)
						(arc
							(start 0.3302 0.4318)
							(mid 0.402042 0.402042)
							(end 0.4318 0.3302)
						)
						(arc
							(start 0.4318 -0.3302)
							(mid 0.402042 -0.402042)
							(end 0.3302 -0.4318)
						)
					)
					(width 0)
					(fill yes)
				)
			)
		)
	)
	(footprint ""
		(layer "F.Cu")
		(at 152.425654 -134.7724 90)
		(property "Reference" "C541"
			(at 0 0 90)
			(layer "F.SilkS")
			(hide yes)
			(effects
				(font
					(size 1.27 1.27)
				)
			)
		)
		(property "Value" "SC1KP50V2KX-1GP"
			(at 1.1811 -2.7051 90)
			(unlocked yes)
			(layer "F.Fab")
			(hide yes)
			(effects
				(font
					(size 1.016 1.016)
					(thickness 0.1524)
				)
			)
		)
		(property "Device Type" "C402H22"
			(at 1.1811 -4.2291 90)
			(unlocked yes)
			(layer "F.Fab")
			(hide yes)
			(effects
				(font
					(size 1.016 1.016)
					(thickness 0.1524)
				)
			)
		)
		(duplicate_pad_numbers_are_jumpers no)
		(fp_rect
			(start -0.4318 0.9525)
			(end 0.4318 -0.9525)
			(stroke
				(width 0)
				(type default)
			)
			(fill no)
			(layer "F.CrtYd")
		)
		(fp_rect
			(start -0.4318 0.9525)
			(end 0.4318 -0.9525)
			(stroke
				(width 0)
				(type default)
			)
			(fill no)
			(layer "F.Fab")
		)
		(pad "1" smd custom
			(at 0 -0.4445 90)
			(size 0.1524 0.1524)
			(layers "F.Cu" "F.Mask" "F.Paste")
			(net "MB0_TEMP_B")
			(options
				(clearance outline)
				(anchor circle)
			)
			(primitives
				(gr_poly
					(pts
						(arc
							(start 0.3048 -0.2032)
							(mid 0.275042 -0.275042)
							(end 0.2032 -0.3048)
						)
						(arc
							(start -0.2032 -0.3048)
							(mid -0.275042 -0.275042)
							(end -0.3048 -0.2032)
						)
						(arc
							(start -0.3048 0.2032)
							(mid -0.275042 0.275042)
							(end -0.2032 0.3048)
						)
						(arc
							(start 0.2032 0.3048)
							(mid 0.275042 0.275042)
							(end 0.3048 0.2032)
						)
					)
					(width 0)
					(fill yes)
				)
			)
		)
		(pad "2" smd custom
			(at 0 0.4445 90)
			(size 0.1524 0.1524)
			(layers "F.Cu" "F.Mask" "F.Paste")
			(net "MB0_TEMP_E")
			(options
				(clearance outline)
				(anchor circle)
			)
			(primitives
				(gr_poly
					(pts
						(arc
							(start 0.3048 -0.2032)
							(mid 0.275042 -0.275042)
							(end 0.2032 -0.3048)
						)
						(arc
							(start -0.2032 -0.3048)
							(mid -0.275042 -0.275042)
							(end -0.3048 -0.2032)
						)
						(arc
							(start -0.3048 0.2032)
							(mid -0.275042 0.275042)
							(end -0.2032 0.3048)
						)
						(arc
							(start 0.2032 0.3048)
							(mid 0.275042 0.275042)
							(end 0.3048 0.2032)
						)
					)
					(width 0)
					(fill yes)
				)
			)
		)
	)
)
